# BASEBOARD_FAB2 (Tioga Pass) — schematic parts with pin connectivity, parts 4637–4649 of 4751; source: Cadence DE-HDL packaged netlist (pstxprt.dat, pstxnet.dat, pstchip.dat)

U1L5  TTL3126  74CBTLV3126 IC  pkg QFNLF  page 112
  1  OE(3)  = PWRGD_PVCCIN_CPU0
  2  A(3)  = XDP_OBSFN_B1_MBP7_N
  3  B(3)  = XDP_CPU_OBSFN_B1_MBP7_N
  4  OE(2)  = PWRGD_PVCCIN_CPU0
  5  A(2)  = XDP_OBSFN_B0_MBP6_N
  6  B(2)  = XDP_CPU_OBSFN_B0_MBP6_N
  8  B(1)  = XDP_CPU_PRDY_N
  9  A(1)  = XDP_PRDY_N
  10  OE(1)  = PWRGD_PVCCIN_CPU0
  11  B(0)  BI  = XDP_CPU_PREQ_N
  12  A(0)  BI  = XDP_PREQ_N
  13  OE(0)  IN  = PWRGD_PVCCIN_CPU0

U1L10  TTL3126  74CBTLV3126 IC  pkg QFNLF  page 189
  1  OE(3)  = BMC_JTAG_SEL_N_MUX
  2  A(3)  = JTAG_PLD_TDO_MUX
  3  B(3)  = JTAG_TDO
  4  OE(2)  = BMC_JTAG_SEL_N_MUX
  5  A(2)  = JTAG_PLD_TCK_MUX
  6  B(2)  = JTAG_TCK
  8  B(1)  = JTAG_TMS
  9  A(1)  = JTAG_PLD_TMS_MUX
  10  OE(1)  = BMC_JTAG_SEL_N_MUX
  11  B(0)  BI  = JTAG_TDI
  12  A(0)  BI  = JTAG_PLD_TDI_MUX
  13  OE(0)  IN  = BMC_JTAG_SEL_N_MUX

U1M1  TTL1G08  NC7SZ08 IC  pkg SOTLF  page 177
  1  A(0)  IN  = LED_SATA_ACT_R_N
  2  B(0)  IN  = LED_SAS_ACT_R_N
  4  Y(0)  OUT  = FP_LED_HDD_ACTIVITY_AND_N

U1M2  NC7SB3157  IC  pkg SMLF  page 113
  1  B1  UNSPEC  = JTAG_MCP_CPU0_TDO
  2  GND  UNSPEC  = GND
  3  B0  UNSPEC  = JTAG_MCP_CPU1_TDO
  4  A  UNSPEC  = JTAG_MCP_MUX_TDO
  5  VCC  UNSPEC  = P3V3_STBY
  6  S  UNSPEC  = FM_CPU1_CD_PRES_N

U1M3  TPS2061  IC  pkg SM  page 176
  1  \out\  OUT  = P5V_USB
  2  GND  GROUND  = GND
  3  OC_N  OUT  = FM_OC0_USB_N
  4  EN_N  IN  = FM_USB_P0_EN_R_N
  5  \in\  IN  = P5V_TPS2061

U1M4  74CBTLV1G125  IC  pkg SMLF  page 112
  1  OE_N  IN  = FM_CPU1_SKTOCC_LVT3_N
  2  A  IN  = XDP_CPU0_TDO
  4  B  OUT  = XDP_CPU1_TDI

U1M5  74CBTLV1G125  IC  pkg SMLF  page 113
  1  OE_N  IN  = FM_CPU0_OR_CPU1_MCP_PRES
  2  A  IN  = P1V8_MCP_CPU0
  4  B  OUT  = JTAG_MCP_TMS_R1

U1M6  74CBTLV1G125  IC  pkg SMLF  page 113
  1  OE_N  IN  = FM_CPU0_AND_CPU1_MCP_PRES
  2  A  IN  = JTAG_MCP_CPU0_TDO
  4  B  OUT  = JTAG_MCP_CPU1_TDI

U1M7  NC7SB3157  IC  pkg SMLF  page 112
  1  B1  UNSPEC  = XDP_CPU0_TDO
  2  GND  UNSPEC  = GND
  3  B0  UNSPEC  = XDP_CPU1_TDO
  4  A  UNSPEC  = XDP_CPU_TDO
  5  VCC  UNSPEC  = P3V3_STBY
  6  S  UNSPEC  = FM_CPU1_SKTOCC_LVT3_N

U1R1  TTL1G07_A  74LVC1G07 IC  pkg SOP  page 170 : 2 = FM_FAST_PROCHOT_THROTTLE_DLY_BU ; 4 = FM_THROTTLE_R1_N

U1R2  TTL1G126_A  74HC1G126 IC  pkg SOT  page 170
  1  OE  IN  = FM_FAST_PROCHOT_EN
  2  A  IN  = FM_FAST_PROCHOT_THROTTLE_DLY_N
  4  Y  OUT  = FM_FAST_PROCHOT_THROTTLE_DLY_BU

U1W2  TCA9517DGKR-GP  pkg DISCRET-G8  page 248
  1  VCCA  POWER  = PVCCIO_CPU0
  2  SCLA  UNSPEC  = SMB_CPU0_PE_HP_GTL_R_SCL
  3  SDAA  UNSPEC  = SMB_CPU0_PE_HP_GTL_R_SDA
  4  GND  POWER  = GND
  5  EN  UNSPEC  = TP_SMB_PEHPCPU0_EN
  6  SDAB  UNSPEC  = SMB_PEHPCPU0_STBY_LVC3_R_SDA
  7  SCLB  UNSPEC  = SMB_PEHPCPU0_STBY_LVC3_R_SCL
  8  VCCB  POWER  = P3V3_STBY

U1W3  PCA9617  IC  pkg SSOP  page 176
  1  VCCA  POWER  = P3V3_STBY
  2  SCLA  IN  = SMB_DEBUG_STBY_LVC3_SCL_CONN
  3  SDAA  IN  = SMB_DEBUG_STBY_LVC3_SDA_CONN
  5  EN  IN  = DEBUG_CARD2_PRSNT
  6  SDAB  OUT  = SMB_DEBUG_STBY_LVC3_SDA_R1
  7  SCLB  OUT  = SMB_DEBUG_STBY_LVC3_SCL_R1
  8  VCCB  POWER  = P3V3_STBY
